(kicad_pcb
	(version 20260206)
	(generator "pcbnew")
	(generator_version "10.0")
	(general
		(thickness 1.6)
		(legacy_teardrops no)
	)
	(paper "A4")
	(title_block
		(title "01162023_DA0F0TEBIF0_F0T_Expander_BD_F_brd_V02_OCP.brd")
		(comment 1 "Grand Teton / footprints 7491-7498 of 9728")
	)
	(layers
		(0 "F.Cu" signal "TOP")
		(4 "In1.Cu" signal "GND")
		(6 "In2.Cu" signal "VCC")
		(8 "In3.Cu" signal "VCC1")
		(10 "In4.Cu" signal "GND1")
		(12 "In5.Cu" signal "IN1")
		(14 "In6.Cu" signal "GND2")
		(16 "In7.Cu" signal "IN2")
		(18 "In8.Cu" signal "GND3")
		(20 "In9.Cu" signal "IN3")
		(22 "In10.Cu" signal "GND4")
		(24 "In11.Cu" signal "IN4")
		(26 "In12.Cu" signal "GND5")
		(28 "In13.Cu" signal "IN5")
		(30 "In14.Cu" signal "GND6")
		(32 "In15.Cu" signal "IN6")
		(34 "In16.Cu" signal "GND7")
		(2 "B.Cu" signal "BOTTOM")
		(9 "F.Adhes" user "F.Adhesive")
		(11 "B.Adhes" user "B.Adhesive")
		(13 "F.Paste" user "Package Geometry/Pastemask Top")
		(15 "B.Paste" user "Package Geometry/Pastemask Bottom")
		(5 "F.SilkS" user "Ref Des/Silkscreen Top")
		(7 "B.SilkS" user "Ref Des/Silkscreen Bottom")
		(1 "F.Mask" user "Board Geometry/Soldermask Top")
		(3 "B.Mask" user "Board Geometry/Soldermask Bottom")
		(17 "Dwgs.User" user "User.Drawings")
		(19 "Cmts.User" user "User.Comments")
		(21 "Eco1.User" user "User.Eco1")
		(23 "Eco2.User" user "User.Eco2")
		(25 "Edge.Cuts" user "Board Geometry/Outline")
		(27 "Margin" user)
		(31 "F.CrtYd" user "Package Geometry/Place Bound Top")
		(29 "B.CrtYd" user "Package Geometry/Place Bound Bottom")
		(35 "F.Fab" user "Ref Des/Assembly Top")
		(33 "B.Fab" user "Ref Des/Assembly Bottom")
	)
	(footprint ""
		(layer "B.Cu")
		(at 403.10054 -85.797898 180)
		(property "Reference" "R6271"
			(at 0 0 0)
			(layer "B.SilkS")
			(hide yes)
			(effects
				(font
					(size 1.27 1.27)
				)
				(justify mirror)
			)
		)
		(property "Value" ""
			(at 0 0 0)
			(layer "B.Fab")
			(effects
				(font
					(size 1.27 1.27)
				)
				(justify mirror)
			)
		)
		(duplicate_pad_numbers_are_jumpers no)
		(fp_line
			(start 0.7874 0.4064)
			(end 0.7874 -0.4064)
			(stroke
				(width 0.1524)
				(type default)
			)
			(layer "B.SilkS")
		)
		(fp_line
			(start 0.7874 -0.4064)
			(end -0.7874 -0.4064)
			(stroke
				(width 0.1524)
				(type default)
			)
			(layer "B.SilkS")
		)
		(fp_line
			(start -0.7874 0.4064)
			(end 0.7874 0.4064)
			(stroke
				(width 0.1524)
				(type default)
			)
			(layer "B.SilkS")
		)
		(fp_line
			(start -0.7874 -0.4064)
			(end -0.7874 0.4064)
			(stroke
				(width 0.1524)
				(type default)
			)
			(layer "B.SilkS")
		)
		(fp_line
			(start 0.67945 0.3048)
			(end 0.67945 -0.305054)
			(stroke
				(width 0.1)
				(type default)
			)
			(layer "B.Fab")
		)
		(fp_line
			(start 0.67945 -0.305054)
			(end 0.12065 -0.305054)
			(stroke
				(width 0.1)
				(type default)
			)
			(layer "B.Fab")
		)
		(fp_line
			(start 0.12065 0.3048)
			(end 0.67945 0.3048)
			(stroke
				(width 0.1)
				(type default)
			)
			(layer "B.Fab")
		)
		(fp_line
			(start 0.12065 0.2794)
			(end 0.12065 0.3048)
			(stroke
				(width 0.1)
				(type default)
			)
			(layer "B.Fab")
		)
		(fp_line
			(start 0.12065 -0.2794)
			(end -0.12065 -0.2794)
			(stroke
				(width 0.1)
				(type default)
			)
			(layer "B.Fab")
		)
		(fp_line
			(start 0.12065 -0.305054)
			(end 0.12065 -0.2794)
			(stroke
				(width 0.1)
				(type default)
			)
			(layer "B.Fab")
		)
		(fp_line
			(start -0.120396 0.3048)
			(end -0.120396 0.2794)
			(stroke
				(width 0.1)
				(type default)
			)
			(layer "B.Fab")
		)
		(fp_line
			(start -0.120396 0.2794)
			(end 0.12065 0.2794)
			(stroke
				(width 0.1)
				(type default)
			)
			(layer "B.Fab")
		)
		(fp_line
			(start -0.12065 -0.2794)
			(end -0.12065 -0.3048)
			(stroke
				(width 0.1)
				(type default)
			)
			(layer "B.Fab")
		)
		(fp_line
			(start -0.12065 -0.3048)
			(end -0.67945 -0.3048)
			(stroke
				(width 0.1)
				(type default)
			)
			(layer "B.Fab")
		)
		(fp_line
			(start -0.67945 0.3048)
			(end -0.120396 0.3048)
			(stroke
				(width 0.1)
				(type default)
			)
			(layer "B.Fab")
		)
		(fp_line
			(start -0.67945 -0.3048)
			(end -0.67945 0.3048)
			(stroke
				(width 0.1)
				(type default)
			)
			(layer "B.Fab")
		)
		(pad "1" smd circle
			(at 0.40005 0)
			(size 0 0)
			(layers "B.Cu" "B.Mask" "B.Paste")
			(net "SMB_BIC_I2C6_MUX_CLK_R_SCL")
		)
		(pad "2" smd circle
			(at -0.40005 0)
			(size 0 0)
			(layers "B.Cu" "B.Mask" "B.Paste")
			(net "SMB_CLK_ISO_SCL")
		)
	)
	(footprint ""
		(layer "B.Cu")
		(at 366.132364 -222.658432)
		(property "Reference" "C2503"
			(at 0 0 0)
			(layer "B.SilkS")
			(hide yes)
			(effects
				(font
					(size 1.27 1.27)
				)
				(justify mirror)
			)
		)
		(property "Value" ""
			(at 0 0 0)
			(layer "B.Fab")
			(effects
				(font
					(size 1.27 1.27)
				)
				(justify mirror)
			)
		)
		(duplicate_pad_numbers_are_jumpers no)
		(fp_line
			(start -0.7874 -0.4064)
			(end -0.7874 0.4064)
			(stroke
				(width 0.1524)
				(type default)
			)
			(layer "B.SilkS")
		)
		(fp_line
			(start -0.7874 0.4064)
			(end 0.7874 0.4064)
			(stroke
				(width 0.1524)
				(type default)
			)
			(layer "B.SilkS")
		)
		(fp_line
			(start 0.7874 -0.4064)
			(end -0.7874 -0.4064)
			(stroke
				(width 0.1524)
				(type default)
			)
			(layer "B.SilkS")
		)
		(fp_line
			(start 0.7874 0.4064)
			(end 0.7874 -0.4064)
			(stroke
				(width 0.1524)
				(type default)
			)
			(layer "B.SilkS")
		)
		(fp_line
			(start -0.67945 -0.3048)
			(end -0.67945 0.3048)
			(stroke
				(width 0.1)
				(type default)
			)
			(layer "B.Fab")
		)
		(fp_line
			(start -0.67945 0.3048)
			(end -0.120396 0.3048)
			(stroke
				(width 0.1)
				(type default)
			)
			(layer "B.Fab")
		)
		(fp_line
			(start -0.12065 -0.3048)
			(end -0.67945 -0.3048)
			(stroke
				(width 0.1)
				(type default)
			)
			(layer "B.Fab")
		)
		(fp_line
			(start -0.12065 -0.2794)
			(end -0.12065 -0.3048)
			(stroke
				(width 0.1)
				(type default)
			)
			(layer "B.Fab")
		)
		(fp_line
			(start -0.120396 0.2794)
			(end 0.12065 0.2794)
			(stroke
				(width 0.1)
				(type default)
			)
			(layer "B.Fab")
		)
		(fp_line
			(start -0.120396 0.3048)
			(end -0.120396 0.2794)
			(stroke
				(width 0.1)
				(type default)
			)
			(layer "B.Fab")
		)
		(fp_line
			(start 0.12065 -0.305054)
			(end 0.12065 -0.2794)
			(stroke
				(width 0.1)
				(type default)
			)
			(layer "B.Fab")
		)
		(fp_line
			(start 0.12065 -0.2794)
			(end -0.12065 -0.2794)
			(stroke
				(width 0.1)
				(type default)
			)
			(layer "B.Fab")
		)
		(fp_line
			(start 0.12065 0.2794)
			(end 0.12065 0.3048)
			(stroke
				(width 0.1)
				(type default)
			)
			(layer "B.Fab")
		)
		(fp_line
			(start 0.12065 0.3048)
			(end 0.67945 0.3048)
			(stroke
				(width 0.1)
				(type default)
			)
			(layer "B.Fab")
		)
		(fp_line
			(start 0.67945 -0.305054)
			(end 0.12065 -0.305054)
			(stroke
				(width 0.1)
				(type default)
			)
			(layer "B.Fab")
		)
		(fp_line
			(start 0.67945 0.3048)
			(end 0.67945 -0.305054)
			(stroke
				(width 0.1)
				(type default)
			)
			(layer "B.Fab")
		)
		(pad "1" smd circle
			(at 0.40005 0 180)
			(size 0 0)
			(layers "B.Cu" "B.Mask" "B.Paste")
			(net "GND")
		)
		(pad "2" smd circle
			(at -0.40005 0 180)
			(size 0 0)
			(layers "B.Cu" "B.Mask" "B.Paste")
			(net "P3V3_AUX")
		)
	)
	(footprint ""
		(layer "B.Cu")
		(at 339.311742 -326.945498 -90)
		(property "Reference" "C4311"
			(at 0 0 90)
			(layer "B.SilkS")
			(hide yes)
			(effects
				(font
					(size 1.27 1.27)
				)
				(justify mirror)
			)
		)
		(property "Value" ""
			(at 0 0 90)
			(layer "B.Fab")
			(effects
				(font
					(size 1.27 1.27)
				)
				(justify mirror)
			)
		)
		(duplicate_pad_numbers_are_jumpers no)
		(fp_line
			(start -1.2954 0.5842)
			(end 1.2954 0.5842)
			(stroke
				(width 0.1524)
				(type default)
			)
			(layer "B.SilkS")
		)
		(fp_line
			(start 1.2954 0.5842)
			(end 1.2954 -0.5842)
			(stroke
				(width 0.1524)
				(type default)
			)
			(layer "B.SilkS")
		)
		(fp_line
			(start -1.2954 -0.5842)
			(end -1.2954 0.5842)
			(stroke
				(width 0.1524)
				(type default)
			)
			(layer "B.SilkS")
		)
		(fp_line
			(start 1.2954 -0.5842)
			(end -1.2954 -0.5842)
			(stroke
				(width 0.1524)
				(type default)
			)
			(layer "B.SilkS")
		)
		(fp_line
			(start -0.8636 0.4572)
			(end 0.8636 0.4572)
			(stroke
				(width 0.1)
				(type default)
			)
			(layer "B.Fab")
		)
		(fp_line
			(start 0.8636 0.4572)
			(end 0.8636 0.4064)
			(stroke
				(width 0.1)
				(type default)
			)
			(layer "B.Fab")
		)
		(fp_line
			(start -1.1938 0.4064)
			(end -0.8636 0.4064)
			(stroke
				(width 0.1)
				(type default)
			)
			(layer "B.Fab")
		)
		(fp_line
			(start -0.8636 0.4064)
			(end -0.8636 0.4572)
			(stroke
				(width 0.1)
				(type default)
			)
			(layer "B.Fab")
		)
		(fp_line
			(start 0.8636 0.4064)
			(end 1.1938 0.4064)
			(stroke
				(width 0.1)
				(type default)
			)
			(layer "B.Fab")
		)
		(fp_line
			(start 1.1938 0.4064)
			(end 1.1938 -0.4064)
			(stroke
				(width 0.1)
				(type default)
			)
			(layer "B.Fab")
		)
		(fp_line
			(start -1.1938 -0.4064)
			(end -1.1938 0.4064)
			(stroke
				(width 0.1)
				(type default)
			)
			(layer "B.Fab")
		)
		(fp_line
			(start -0.8636 -0.4064)
			(end -1.1938 -0.4064)
			(stroke
				(width 0.1)
				(type default)
			)
			(layer "B.Fab")
		)
		(fp_line
			(start 0.8636 -0.4064)
			(end 0.8636 -0.4572)
			(stroke
				(width 0.1)
				(type default)
			)
			(layer "B.Fab")
		)
		(fp_line
			(start 1.1938 -0.4064)
			(end 0.8636 -0.4064)
			(stroke
				(width 0.1)
				(type default)
			)
			(layer "B.Fab")
		)
		(fp_line
			(start -0.8636 -0.4572)
			(end -0.8636 -0.4064)
			(stroke
				(width 0.1)
				(type default)
			)
			(layer "B.Fab")
		)
		(fp_line
			(start 0.8636 -0.4572)
			(end -0.8636 -0.4572)
			(stroke
				(width 0.1)
				(type default)
			)
			(layer "B.Fab")
		)
		(pad "1" smd rect
			(at 0.7366 0 180)
			(size 0.7112 0.8128)
			(layers "B.Cu" "B.Mask" "B.Paste")
			(net "P0V8_SERDES_VDDA_PEX2_C1")
		)
		(pad "2" smd rect
			(at -0.7366 0 180)
			(size 0.7112 0.8128)
			(layers "B.Cu" "B.Mask" "B.Paste")
			(net "GND")
		)
	)
	(footprint ""
		(layer "B.Cu")
		(at 193.641726 -99.037648 180)
		(property "Reference" "R167"
			(at 0 0 0)
			(layer "B.SilkS")
			(hide yes)
			(effects
				(font
					(size 1.27 1.27)
				)
				(justify mirror)
			)
		)
		(property "Value" ""
			(at 0 0 0)
			(layer "B.Fab")
			(effects
				(font
					(size 1.27 1.27)
				)
				(justify mirror)
			)
		)
		(duplicate_pad_numbers_are_jumpers no)
		(fp_line
			(start 0.7874 0.4064)
			(end 0.7874 -0.4064)
			(stroke
				(width 0.1524)
				(type default)
			)
			(layer "B.SilkS")
		)
		(fp_line
			(start 0.7874 -0.4064)
			(end -0.7874 -0.4064)
			(stroke
				(width 0.1524)
				(type default)
			)
			(layer "B.SilkS")
		)
		(fp_line
			(start -0.7874 0.4064)
			(end 0.7874 0.4064)
			(stroke
				(width 0.1524)
				(type default)
			)
			(layer "B.SilkS")
		)
		(fp_line
			(start -0.7874 -0.4064)
			(end -0.7874 0.4064)
			(stroke
				(width 0.1524)
				(type default)
			)
			(layer "B.SilkS")
		)
		(fp_line
			(start 0.67945 0.3048)
			(end 0.67945 -0.305054)
			(stroke
				(width 0.1)
				(type default)
			)
			(layer "B.Fab")
		)
		(fp_line
			(start 0.67945 -0.305054)
			(end 0.12065 -0.305054)
			(stroke
				(width 0.1)
				(type default)
			)
			(layer "B.Fab")
		)
		(fp_line
			(start 0.12065 0.3048)
			(end 0.67945 0.3048)
			(stroke
				(width 0.1)
				(type default)
			)
			(layer "B.Fab")
		)
		(fp_line
			(start 0.12065 0.2794)
			(end 0.12065 0.3048)
			(stroke
				(width 0.1)
				(type default)
			)
			(layer "B.Fab")
		)
		(fp_line
			(start 0.12065 -0.2794)
			(end -0.12065 -0.2794)
			(stroke
				(width 0.1)
				(type default)
			)
			(layer "B.Fab")
		)
		(fp_line
			(start 0.12065 -0.305054)
			(end 0.12065 -0.2794)
			(stroke
				(width 0.1)
				(type default)
			)
			(layer "B.Fab")
		)
		(fp_line
			(start -0.120396 0.3048)
			(end -0.120396 0.2794)
			(stroke
				(width 0.1)
				(type default)
			)
			(layer "B.Fab")
		)
		(fp_line
			(start -0.120396 0.2794)
			(end 0.12065 0.2794)
			(stroke
				(width 0.1)
				(type default)
			)
			(layer "B.Fab")
		)
		(fp_line
			(start -0.12065 -0.2794)
			(end -0.12065 -0.3048)
			(stroke
				(width 0.1)
				(type default)
			)
			(layer "B.Fab")
		)
		(fp_line
			(start -0.12065 -0.3048)
			(end -0.67945 -0.3048)
			(stroke
				(width 0.1)
				(type default)
			)
			(layer "B.Fab")
		)
		(fp_line
			(start -0.67945 0.3048)
			(end -0.120396 0.3048)
			(stroke
				(width 0.1)
				(type default)
			)
			(layer "B.Fab")
		)
		(fp_line
			(start -0.67945 -0.3048)
			(end -0.67945 0.3048)
			(stroke
				(width 0.1)
				(type default)
			)
			(layer "B.Fab")
		)
		(pad "1" smd circle
			(at 0.40005 0)
			(size 0 0)
			(layers "B.Cu" "B.Mask" "B.Paste")
			(net "NIC3_CLK")
		)
		(pad "2" smd circle
			(at -0.40005 0)
			(size 0 0)
			(layers "B.Cu" "B.Mask" "B.Paste")
			(net "GND")
		)
	)
	(footprint ""
		(layer "B.Cu")
		(at 60.599828 -303.499774 -90)
		(property "Reference" "C2901"
			(at 0 0 90)
			(layer "B.SilkS")
			(hide yes)
			(effects
				(font
					(size 1.27 1.27)
				)
				(justify mirror)
			)
		)
		(property "Value" ""
			(at 0 0 90)
			(layer "B.Fab")
			(effects
				(font
					(size 1.27 1.27)
				)
				(justify mirror)
			)
		)
		(duplicate_pad_numbers_are_jumpers no)
		(fp_line
			(start -0.299974 0.150114)
			(end 0.299974 0.150114)
			(stroke
				(width 0.1)
				(type default)
			)
			(layer "B.Fab")
		)
		(fp_line
			(start 0.299974 0.150114)
			(end 0.299974 -0.150114)
			(stroke
				(width 0.1)
				(type default)
			)
			(layer "B.Fab")
		)
		(fp_line
			(start -0.299974 -0.150114)
			(end -0.299974 0.150114)
			(stroke
				(width 0.1)
				(type default)
			)
			(layer "B.Fab")
		)
		(fp_line
			(start 0.299974 -0.150114)
			(end -0.299974 -0.150114)
			(stroke
				(width 0.1)
				(type default)
			)
			(layer "B.Fab")
		)
		(pad "1" smd rect
			(at 0.2667 0 90)
			(size 0.3048 0.381)
			(layers "B.Cu" "B.Mask" "B.Paste")
			(net "P1V25_PEX0")
		)
		(pad "2" smd rect
			(at -0.2667 0 90)
			(size 0.3048 0.381)
			(layers "B.Cu" "B.Mask" "B.Paste")
			(net "GND")
		)
	)
	(footprint ""
		(layer "B.Cu")
		(at 207.180942 -259.311648 90)
		(property "Reference" "R6345"
			(at 0 0 90)
			(layer "B.SilkS")
			(hide yes)
			(effects
				(font
					(size 1.27 1.27)
				)
				(justify mirror)
			)
		)
		(property "Value" ""
			(at 0 0 90)
			(layer "B.Fab")
			(effects
				(font
					(size 1.27 1.27)
				)
				(justify mirror)
			)
		)
		(duplicate_pad_numbers_are_jumpers no)
		(fp_line
			(start 0.7874 -0.4064)
			(end -0.7874 -0.4064)
			(stroke
				(width 0.1524)
				(type default)
			)
			(layer "B.SilkS")
		)
		(fp_line
			(start -0.7874 -0.4064)
			(end -0.7874 0.4064)
			(stroke
				(width 0.1524)
				(type default)
			)
			(layer "B.SilkS")
		)
		(fp_line
			(start 0.7874 0.4064)
			(end 0.7874 -0.4064)
			(stroke
				(width 0.1524)
				(type default)
			)
			(layer "B.SilkS")
		)
		(fp_line
			(start -0.7874 0.4064)
			(end 0.7874 0.4064)
			(stroke
				(width 0.1524)
				(type default)
			)
			(layer "B.SilkS")
		)
		(fp_line
			(start 0.67945 -0.305054)
			(end 0.12065 -0.305054)
			(stroke
				(width 0.1)
				(type default)
			)
			(layer "B.Fab")
		)
		(fp_line
			(start 0.12065 -0.305054)
			(end 0.12065 -0.2794)
			(stroke
				(width 0.1)
				(type default)
			)
			(layer "B.Fab")
		)
		(fp_line
			(start -0.12065 -0.3048)
			(end -0.67945 -0.3048)
			(stroke
				(width 0.1)
				(type default)
			)
			(layer "B.Fab")
		)
		(fp_line
			(start -0.67945 -0.3048)
			(end -0.67945 0.3048)
			(stroke
				(width 0.1)
				(type default)
			)
			(layer "B.Fab")
		)
		(fp_line
			(start 0.12065 -0.2794)
			(end -0.12065 -0.2794)
			(stroke
				(width 0.1)
				(type default)
			)
			(layer "B.Fab")
		)
		(fp_line
			(start -0.12065 -0.2794)
			(end -0.12065 -0.3048)
			(stroke
				(width 0.1)
				(type default)
			)
			(layer "B.Fab")
		)
		(fp_line
			(start 0.12065 0.2794)
			(end 0.12065 0.3048)
			(stroke
				(width 0.1)
				(type default)
			)
			(layer "B.Fab")
		)
		(fp_line
			(start -0.120396 0.2794)
			(end 0.12065 0.2794)
			(stroke
				(width 0.1)
				(type default)
			)
			(layer "B.Fab")
		)
		(fp_line
			(start 0.67945 0.3048)
			(end 0.67945 -0.305054)
			(stroke
				(width 0.1)
				(type default)
			)
			(layer "B.Fab")
		)
		(fp_line
			(start 0.12065 0.3048)
			(end 0.67945 0.3048)
			(stroke
				(width 0.1)
				(type default)
			)
			(layer "B.Fab")
		)
		(fp_line
			(start -0.120396 0.3048)
			(end -0.120396 0.2794)
			(stroke
				(width 0.1)
				(type default)
			)
			(layer "B.Fab")
		)
		(fp_line
			(start -0.67945 0.3048)
			(end -0.120396 0.3048)
			(stroke
				(width 0.1)
				(type default)
			)
			(layer "B.Fab")
		)
		(pad "1" smd circle
			(at 0.40005 0 270)
			(size 0 0)
			(layers "B.Cu" "B.Mask" "B.Paste")
			(net "P1V8_PEX")
		)
		(pad "2" smd circle
			(at -0.40005 0 270)
			(size 0 0)
			(layers "B.Cu" "B.Mask" "B.Paste")
			(net "SMB_PEX1_MUX_SCL")
		)
	)
	(footprint ""
		(layer "B.Cu")
		(at 59.649868 -301.599854 -90)
		(property "Reference" "C1228"
			(at 0 0 90)
			(layer "B.SilkS")
			(hide yes)
			(effects
				(font
					(size 1.27 1.27)
				)
				(justify mirror)
			)
		)
		(property "Value" ""
			(at 0 0 90)
			(layer "B.Fab")
			(effects
				(font
					(size 1.27 1.27)
				)
				(justify mirror)
			)
		)
		(duplicate_pad_numbers_are_jumpers no)
		(fp_line
			(start -0.299974 0.150114)
			(end 0.299974 0.150114)
			(stroke
				(width 0.1)
				(type default)
			)
			(layer "B.Fab")
		)
		(fp_line
			(start 0.299974 0.150114)
			(end 0.299974 -0.150114)
			(stroke
				(width 0.1)
				(type default)
			)
			(layer "B.Fab")
		)
		(fp_line
			(start -0.299974 -0.150114)
			(end -0.299974 0.150114)
			(stroke
				(width 0.1)
				(type default)
			)
			(layer "B.Fab")
		)
		(fp_line
			(start 0.299974 -0.150114)
			(end -0.299974 -0.150114)
			(stroke
				(width 0.1)
				(type default)
			)
			(layer "B.Fab")
		)
		(pad "1" smd rect
			(at 0.2667 0 90)
			(size 0.3048 0.381)
			(layers "B.Cu" "B.Mask" "B.Paste")
			(net "P0V8_SERDES_VDDA_PEX0")
		)
		(pad "2" smd rect
			(at -0.2667 0 90)
			(size 0.3048 0.381)
			(layers "B.Cu" "B.Mask" "B.Paste")
			(net "GND")
		)
	)
	(footprint ""
		(layer "B.Cu")
		(at 52.524914 -286.399732 90)
		(property "Reference" "C2981"
			(at 0 0 90)
			(layer "B.SilkS")
			(hide yes)
			(effects
				(font
					(size 1.27 1.27)
				)
				(justify mirror)
			)
		)
		(property "Value" ""
			(at 0 0 90)
			(layer "B.Fab")
			(effects
				(font
					(size 1.27 1.27)
				)
				(justify mirror)
			)
		)
		(duplicate_pad_numbers_are_jumpers no)
		(fp_line
			(start 0.299974 -0.150114)
			(end -0.299974 -0.150114)
			(stroke
				(width 0.1)
				(type default)
			)
			(layer "B.Fab")
		)
		(fp_line
			(start -0.299974 -0.150114)
			(end -0.299974 0.150114)
			(stroke
				(width 0.1)
				(type default)
			)
			(layer "B.Fab")
		)
		(fp_line
			(start 0.299974 0.150114)
			(end 0.299974 -0.150114)
			(stroke
				(width 0.1)
				(type default)
			)
			(layer "B.Fab")
		)
		(fp_line
			(start -0.299974 0.150114)
			(end 0.299974 0.150114)
			(stroke
				(width 0.1)
				(type default)
			)
			(layer "B.Fab")
		)
		(pad "1" smd rect
			(at 0.2667 0 270)
			(size 0.3048 0.381)
			(layers "B.Cu" "B.Mask" "B.Paste")
			(net "P1V25_SERDES_VDDPLL_PEX0")
		)
		(pad "2" smd rect
			(at -0.2667 0 270)
			(size 0.3048 0.381)
			(layers "B.Cu" "B.Mask" "B.Paste")
			(net "GND")
		)
	)
)
